(kicad_pcb
	(version 20260206)
	(generator "pcbnew")
	(generator_version "10.0")
	(general
		(thickness 1.6)
		(legacy_teardrops no)
	)
	(paper "A4")
	(title_block
		(title "Wiwynn_Tioga_Pass_MB.brd")
		(comment 1 "Tioga Pass / footprints 831-837 of 4770")
	)
	(layers
		(0 "F.Cu" signal "TOP")
		(4 "In1.Cu" signal "L2GND")
		(6 "In2.Cu" signal "L3")
		(8 "In3.Cu" signal "L4GND")
		(10 "In4.Cu" signal "L5")
		(12 "In5.Cu" signal "L6GND")
		(14 "In6.Cu" signal "L7VCC")
		(16 "In7.Cu" signal "L8VCC")
		(18 "In8.Cu" signal "L9GND")
		(20 "In9.Cu" signal "L10")
		(22 "In10.Cu" signal "L11GND")
		(24 "In11.Cu" signal "L12")
		(26 "In12.Cu" signal "L13GND")
		(2 "B.Cu" signal "BOTTOM")
		(9 "F.Adhes" user "F.Adhesive")
		(11 "B.Adhes" user "B.Adhesive")
		(13 "F.Paste" user "Package Geometry/Pastemask Top")
		(15 "B.Paste" user "Package Geometry/Pastemask Bottom")
		(5 "F.SilkS" user "Ref Des/Silkscreen Top")
		(7 "B.SilkS" user "Ref Des/Silkscreen Bottom")
		(1 "F.Mask" user "Board Geometry/Soldermask Top")
		(3 "B.Mask" user "Board Geometry/Soldermask Bottom")
		(17 "Dwgs.User" user "User.Drawings")
		(19 "Cmts.User" user "User.Comments")
		(21 "Eco1.User" user "User.Eco1")
		(23 "Eco2.User" user "User.Eco2")
		(25 "Edge.Cuts" user "Board Geometry/Outline")
		(27 "Margin" user)
		(31 "F.CrtYd" user "Package Geometry/Place Bound Top")
		(29 "B.CrtYd" user "Package Geometry/Place Bound Bottom")
		(35 "F.Fab" user "Ref Des/Assembly Top")
		(33 "B.Fab" user "Ref Des/Assembly Bottom")
	)
	(footprint ""
		(layer "F.Cu")
		(at 335.788 -23.241)
		(property "Reference" "R7F17"
			(at 0 0 0)
			(layer "F.SilkS")
			(hide yes)
			(effects
				(font
					(size 1.27 1.27)
				)
			)
		)
		(property "Value" ""
			(at 0 0 0)
			(layer "F.Fab")
			(effects
				(font
					(size 1.27 1.27)
				)
			)
		)
		(duplicate_pad_numbers_are_jumpers no)
		(fp_poly
			(pts
				(xy -0.2794 -0.1016) (xy 0.2794 -0.1016) (xy 0.2794 0.9906) (xy -0.2794 0.9906)
			)
			(stroke
				(width 0)
				(type default)
			)
			(fill no)
			(layer "F.CrtYd")
		)
		(fp_line
			(start -0.2794 -0.1016)
			(end -0.2794 0.9906)
			(stroke
				(width 0.1)
				(type default)
			)
			(layer "F.Fab")
		)
		(fp_line
			(start -0.2794 0.9906)
			(end 0.2794 0.9906)
			(stroke
				(width 0.1)
				(type default)
			)
			(layer "F.Fab")
		)
		(fp_line
			(start 0.2794 -0.1016)
			(end -0.2794 -0.1016)
			(stroke
				(width 0.1)
				(type default)
			)
			(layer "F.Fab")
		)
		(fp_line
			(start 0.2794 0.9906)
			(end 0.2794 -0.1016)
			(stroke
				(width 0.1)
				(type default)
			)
			(layer "F.Fab")
		)
		(pad "1" smd rect
			(at 0 0)
			(size 0.508 0.508)
			(layers "F.Cu" "F.Mask" "F.Paste")
			(net "VSENSE_PVPP_ABC")
		)
		(pad "2" smd rect
			(at 0 0.889)
			(size 0.508 0.508)
			(layers "F.Cu" "F.Mask" "F.Paste")
			(net "VR_COMP_PVPP_ABC")
		)
		(zone
			(layer "F.Cu")
			(hatch none 0.5)
			(connect_pads
				(clearance 0)
			)
			(min_thickness 0.25)
			(keepout
				(tracks allowed)
				(vias not_allowed)
				(pads allowed)
				(copperpour not_allowed)
				(footprints allowed)
			)
			(placement
				(enabled no)
				(sheetname "")
			)
			(fill
				(thermal_gap 0.5)
				(thermal_bridge_width 0.5)
				(island_removal_mode 0)
			)
			(polygon
				(pts
					(xy 335.534 -22.987) (xy 336.042 -22.987) (xy 336.042 -22.606) (xy 335.534 -22.606)
				)
			)
		)
		(zone
			(layer "F.Cu")
			(hatch none 0.5)
			(connect_pads
				(clearance 0)
			)
			(min_thickness 0.25)
			(keepout
				(tracks not_allowed)
				(vias allowed)
				(pads allowed)
				(copperpour not_allowed)
				(footprints allowed)
			)
			(placement
				(enabled no)
				(sheetname "")
			)
			(fill
				(thermal_gap 0.5)
				(thermal_bridge_width 0.5)
				(island_removal_mode 0)
			)
			(polygon
				(pts
					(xy 335.534 -22.606) (xy 336.042 -22.606) (xy 336.042 -22.987) (xy 335.534 -22.987)
				)
			)
		)
	)
	(footprint ""
		(layer "F.Cu")
		(at 467.36 -132.715 180)
		(property "Reference" "R9B12"
			(at 0 0 180)
			(layer "F.SilkS")
			(hide yes)
			(effects
				(font
					(size 1.27 1.27)
				)
			)
		)
		(property "Value" ""
			(at 0 0 180)
			(layer "F.Fab")
			(effects
				(font
					(size 1.27 1.27)
				)
			)
		)
		(duplicate_pad_numbers_are_jumpers no)
		(fp_poly
			(pts
				(xy -0.2794 -0.1016) (xy 0.2794 -0.1016) (xy 0.2794 0.9906) (xy -0.2794 0.9906)
			)
			(stroke
				(width 0)
				(type default)
			)
			(fill no)
			(layer "F.CrtYd")
		)
		(fp_line
			(start 0.2794 0.9906)
			(end 0.2794 -0.1016)
			(stroke
				(width 0.1)
				(type default)
			)
			(layer "F.Fab")
		)
		(fp_line
			(start 0.2794 -0.1016)
			(end -0.2794 -0.1016)
			(stroke
				(width 0.1)
				(type default)
			)
			(layer "F.Fab")
		)
		(fp_line
			(start -0.2794 0.9906)
			(end 0.2794 0.9906)
			(stroke
				(width 0.1)
				(type default)
			)
			(layer "F.Fab")
		)
		(fp_line
			(start -0.2794 -0.1016)
			(end -0.2794 0.9906)
			(stroke
				(width 0.1)
				(type default)
			)
			(layer "F.Fab")
		)
		(pad "1" smd rect
			(at 0 0 180)
			(size 0.508 0.508)
			(layers "F.Cu" "F.Mask" "F.Paste")
			(net "P1V8_MCP_CPU0")
		)
		(pad "2" smd rect
			(at 0 0.889 180)
			(size 0.508 0.508)
			(layers "F.Cu" "F.Mask" "F.Paste")
			(net "JTAG_MCP_MUX_TDO")
		)
		(zone
			(layer "F.Cu")
			(hatch none 0.5)
			(connect_pads
				(clearance 0)
			)
			(min_thickness 0.25)
			(keepout
				(tracks not_allowed)
				(vias allowed)
				(pads allowed)
				(copperpour not_allowed)
				(footprints allowed)
			)
			(placement
				(enabled no)
				(sheetname "")
			)
			(fill
				(thermal_gap 0.5)
				(thermal_bridge_width 0.5)
				(island_removal_mode 0)
			)
			(polygon
				(pts
					(xy 467.614 -133.35) (xy 467.106 -133.35) (xy 467.106 -132.969) (xy 467.614 -132.969)
				)
			)
		)
		(zone
			(layer "F.Cu")
			(hatch none 0.5)
			(connect_pads
				(clearance 0)
			)
			(min_thickness 0.25)
			(keepout
				(tracks allowed)
				(vias not_allowed)
				(pads allowed)
				(copperpour not_allowed)
				(footprints allowed)
			)
			(placement
				(enabled no)
				(sheetname "")
			)
			(fill
				(thermal_gap 0.5)
				(thermal_bridge_width 0.5)
				(island_removal_mode 0)
			)
			(polygon
				(pts
					(xy 467.614 -132.969) (xy 467.106 -132.969) (xy 467.106 -133.35) (xy 467.614 -133.35)
				)
			)
		)
	)
	(footprint ""
		(layer "F.Cu")
		(at 437.388 -19.4945)
		(property "Reference" "R10W1"
			(at -0.8382 -0.67818 0)
			(unlocked yes)
			(layer "F.SilkS")
			(effects
				(font
					(size 0.4064 0.254)
					(thickness 0.1524)
				)
				(justify left)
			)
		)
		(property "Value" ""
			(at 0 0 0)
			(layer "F.Fab")
			(effects
				(font
					(size 1.27 1.27)
				)
			)
		)
		(duplicate_pad_numbers_are_jumpers no)
		(fp_poly
			(pts
				(xy -0.2794 -0.1016) (xy 0.2794 -0.1016) (xy 0.2794 0.9906) (xy -0.2794 0.9906)
			)
			(stroke
				(width 0)
				(type default)
			)
			(fill no)
			(layer "F.CrtYd")
		)
		(fp_line
			(start -0.2794 -0.1016)
			(end -0.2794 0.9906)
			(stroke
				(width 0.1)
				(type default)
			)
			(layer "F.Fab")
		)
		(fp_line
			(start -0.2794 0.9906)
			(end 0.2794 0.9906)
			(stroke
				(width 0.1)
				(type default)
			)
			(layer "F.Fab")
		)
		(fp_line
			(start 0.2794 -0.1016)
			(end -0.2794 -0.1016)
			(stroke
				(width 0.1)
				(type default)
			)
			(layer "F.Fab")
		)
		(fp_line
			(start 0.2794 0.9906)
			(end 0.2794 -0.1016)
			(stroke
				(width 0.1)
				(type default)
			)
			(layer "F.Fab")
		)
		(pad "1" smd rect
			(at 0 0)
			(size 0.508 0.508)
			(layers "F.Cu" "F.Mask" "F.Paste")
			(net "PUMP_TACH0")
		)
		(pad "2" smd rect
			(at 0 0.889)
			(size 0.508 0.508)
			(layers "F.Cu" "F.Mask" "F.Paste")
			(net "PUMP_TACH_R")
		)
		(zone
			(layer "F.Cu")
			(hatch none 0.5)
			(connect_pads
				(clearance 0)
			)
			(min_thickness 0.25)
			(keepout
				(tracks allowed)
				(vias not_allowed)
				(pads allowed)
				(copperpour not_allowed)
				(footprints allowed)
			)
			(placement
				(enabled no)
				(sheetname "")
			)
			(fill
				(thermal_gap 0.5)
				(thermal_bridge_width 0.5)
				(island_removal_mode 0)
			)
			(polygon
				(pts
					(xy 437.134 -19.2405) (xy 437.642 -19.2405) (xy 437.642 -18.8595) (xy 437.134 -18.8595)
				)
			)
		)
		(zone
			(layer "F.Cu")
			(hatch none 0.5)
			(connect_pads
				(clearance 0)
			)
			(min_thickness 0.25)
			(keepout
				(tracks not_allowed)
				(vias allowed)
				(pads allowed)
				(copperpour not_allowed)
				(footprints allowed)
			)
			(placement
				(enabled no)
				(sheetname "")
			)
			(fill
				(thermal_gap 0.5)
				(thermal_bridge_width 0.5)
				(island_removal_mode 0)
			)
			(polygon
				(pts
					(xy 437.134 -18.8595) (xy 437.642 -18.8595) (xy 437.642 -19.2405) (xy 437.134 -19.2405)
				)
			)
		)
	)
	(footprint ""
		(layer "F.Cu")
		(at 179.578 -67.437 -90)
		(property "Reference" "C4D42"
			(at 0 0 270)
			(layer "F.SilkS")
			(hide yes)
			(effects
				(font
					(size 1.27 1.27)
				)
			)
		)
		(property "Value" ""
			(at 0 0 270)
			(layer "F.Fab")
			(effects
				(font
					(size 1.27 1.27)
				)
			)
		)
		(duplicate_pad_numbers_are_jumpers no)
		(fp_poly
			(pts
				(xy 0.3048 -0.1016) (xy 0.3048 0.9906) (xy -0.3048 0.9906) (xy -0.3048 -0.1016)
			)
			(stroke
				(width 0)
				(type default)
			)
			(fill no)
			(layer "F.CrtYd")
		)
		(fp_line
			(start -0.3048 0.9906)
			(end 0.3048 0.9906)
			(stroke
				(width 0.1)
				(type default)
			)
			(layer "F.Fab")
		)
		(fp_line
			(start 0.3048 0.9906)
			(end 0.3048 -0.1016)
			(stroke
				(width 0.1)
				(type default)
			)
			(layer "F.Fab")
		)
		(fp_line
			(start -0.3048 -0.1016)
			(end -0.3048 0.9906)
			(stroke
				(width 0.1)
				(type default)
			)
			(layer "F.Fab")
		)
		(fp_line
			(start 0.3048 -0.1016)
			(end -0.3048 -0.1016)
			(stroke
				(width 0.1)
				(type default)
			)
			(layer "F.Fab")
		)
		(pad "1" smd rect
			(at 0 0 270)
			(size 0.508 0.508)
			(layers "F.Cu" "F.Mask" "F.Paste")
			(net "VR_VRRDY_PVCCIN_CPU0")
		)
		(pad "2" smd rect
			(at 0 0.889 270)
			(size 0.508 0.508)
			(layers "F.Cu" "F.Mask" "F.Paste")
			(net "GND")
		)
		(zone
			(layer "F.Cu")
			(hatch none 0.5)
			(connect_pads
				(clearance 0)
			)
			(min_thickness 0.25)
			(keepout
				(tracks not_allowed)
				(vias allowed)
				(pads allowed)
				(copperpour not_allowed)
				(footprints allowed)
			)
			(placement
				(enabled no)
				(sheetname "")
			)
			(fill
				(thermal_gap 0.5)
				(thermal_bridge_width 0.5)
				(island_removal_mode 0)
			)
			(polygon
				(pts
					(xy 178.943 -67.691) (xy 178.943 -67.183) (xy 179.324 -67.183) (xy 179.324 -67.691)
				)
			)
		)
		(zone
			(layer "F.Cu")
			(hatch none 0.5)
			(connect_pads
				(clearance 0)
			)
			(min_thickness 0.25)
			(keepout
				(tracks allowed)
				(vias not_allowed)
				(pads allowed)
				(copperpour not_allowed)
				(footprints allowed)
			)
			(placement
				(enabled no)
				(sheetname "")
			)
			(fill
				(thermal_gap 0.5)
				(thermal_bridge_width 0.5)
				(island_removal_mode 0)
			)
			(polygon
				(pts
					(xy 179.324 -67.691) (xy 179.324 -67.183) (xy 178.943 -67.183) (xy 178.943 -67.691)
				)
			)
		)
	)
	(footprint ""
		(layer "F.Cu")
		(at 24.03602 -89.7509 180)
		(property "Reference" "RF9"
			(at -0.8382 -0.67818 180)
			(unlocked yes)
			(layer "F.SilkS")
			(effects
				(font
					(size 0.4064 0.254)
					(thickness 0.1524)
				)
				(justify left)
			)
		)
		(property "Value" ""
			(at 0 0 180)
			(layer "F.Fab")
			(effects
				(font
					(size 1.27 1.27)
				)
			)
		)
		(duplicate_pad_numbers_are_jumpers no)
		(fp_poly
			(pts
				(xy -0.2794 -0.1016) (xy 0.2794 -0.1016) (xy 0.2794 0.9906) (xy -0.2794 0.9906)
			)
			(stroke
				(width 0)
				(type default)
			)
			(fill no)
			(layer "F.CrtYd")
		)
		(fp_line
			(start 0.2794 0.9906)
			(end 0.2794 -0.1016)
			(stroke
				(width 0.1)
				(type default)
			)
			(layer "F.Fab")
		)
		(fp_line
			(start 0.2794 -0.1016)
			(end -0.2794 -0.1016)
			(stroke
				(width 0.1)
				(type default)
			)
			(layer "F.Fab")
		)
		(fp_line
			(start -0.2794 0.9906)
			(end 0.2794 0.9906)
			(stroke
				(width 0.1)
				(type default)
			)
			(layer "F.Fab")
		)
		(fp_line
			(start -0.2794 -0.1016)
			(end -0.2794 0.9906)
			(stroke
				(width 0.1)
				(type default)
			)
			(layer "F.Fab")
		)
		(pad "1" smd rect
			(at 0 0 180)
			(size 0.508 0.508)
			(layers "F.Cu" "F.Mask" "F.Paste")
			(net "VR_PVCCIN_CPU1_AIREF3")
		)
		(pad "2" smd rect
			(at 0 0.889 180)
			(size 0.508 0.508)
			(layers "F.Cu" "F.Mask" "F.Paste")
			(net "ISENSE_PVCCIN_CPU1_PH3_IMON")
		)
		(zone
			(layer "F.Cu")
			(hatch none 0.5)
			(connect_pads
				(clearance 0)
			)
			(min_thickness 0.25)
			(keepout
				(tracks not_allowed)
				(vias allowed)
				(pads allowed)
				(copperpour not_allowed)
				(footprints allowed)
			)
			(placement
				(enabled no)
				(sheetname "")
			)
			(fill
				(thermal_gap 0.5)
				(thermal_bridge_width 0.5)
				(island_removal_mode 0)
			)
			(polygon
				(pts
					(xy 24.29002 -90.3859) (xy 23.78202 -90.3859) (xy 23.78202 -90.0049) (xy 24.29002 -90.0049)
				)
			)
		)
		(zone
			(layer "F.Cu")
			(hatch none 0.5)
			(connect_pads
				(clearance 0)
			)
			(min_thickness 0.25)
			(keepout
				(tracks allowed)
				(vias not_allowed)
				(pads allowed)
				(copperpour not_allowed)
				(footprints allowed)
			)
			(placement
				(enabled no)
				(sheetname "")
			)
			(fill
				(thermal_gap 0.5)
				(thermal_bridge_width 0.5)
				(island_removal_mode 0)
			)
			(polygon
				(pts
					(xy 24.29002 -90.0049) (xy 23.78202 -90.0049) (xy 23.78202 -90.3859) (xy 24.29002 -90.3859)
				)
			)
		)
	)
	(footprint ""
		(layer "F.Cu")
		(at -2.8702 -10.8077 -90)
		(property "Reference" "C1G12"
			(at 0 0 270)
			(layer "F.SilkS")
			(hide yes)
			(effects
				(font
					(size 1.27 1.27)
				)
			)
		)
		(property "Value" "*"
			(at -2.3114 0.10795 270)
			(unlocked yes)
			(layer "F.Fab")
			(hide yes)
			(effects
				(font
					(size 0.889 0.889)
					(thickness 0.1524)
				)
			)
		)
		(property "Device Type" "ST270U2D5VBM-GP_SMD-TCG2-ST270A"
			(at -2.3114 -1.41605 270)
			(unlocked yes)
			(layer "F.Fab")
			(hide yes)
			(effects
				(font
					(size 0.889 0.889)
					(thickness 0.1524)
				)
			)
		)
		(duplicate_pad_numbers_are_jumpers no)
		(fp_line
			(start -1.5494 0.4826)
			(end -1.5494 -0.4826)
			(stroke
				(width 0.1524)
				(type default)
			)
			(layer "F.SilkS")
		)
		(fp_line
			(start 1.5494 -0.4826)
			(end 1.5494 0.4826)
			(stroke
				(width 0.1524)
				(type default)
			)
			(layer "F.SilkS")
		)
		(fp_line
			(start -1.0922 -2.35458)
			(end 1.0922 -2.35458)
			(stroke
				(width 0.508)
				(type default)
			)
			(layer "F.SilkS")
		)
		(fp_poly
			(pts
				(xy -1.3462 1.9558) (xy -1.3462 1.905) (xy -1.5494 1.905) (xy -1.5494 -1.905) (xy -1.3462 -1.905)
				(xy -1.3462 -1.9558) (xy 1.3462 -1.9558) (xy 1.3462 -1.905) (xy 1.5494 -1.905) (xy 1.5494 1.905)
				(xy 1.3462 1.905) (xy 1.3462 1.9558)
			)
			(stroke
				(width 0)
				(type default)
			)
			(fill no)
			(layer "F.CrtYd")
		)
		(fp_poly
			(pts
				(xy -1.3462 1.9558) (xy -1.3462 1.905) (xy -1.5494 1.905) (xy -1.5494 -1.905) (xy -1.3462 -1.905)
				(xy -1.3462 -1.9558) (xy 1.3462 -1.9558) (xy 1.3462 -1.905) (xy 1.5494 -1.905) (xy 1.5494 1.905)
				(xy 1.3462 1.905) (xy 1.3462 1.9558)
			)
			(stroke
				(width 0)
				(type default)
			)
			(fill no)
			(layer "F.Fab")
		)
		(pad "1" smd rect
			(at 0 -1.27508 270)
			(size 2.6924 1.3462)
			(layers "F.Cu" "F.Mask" "F.Paste")
			(net "VR_FET_SW_P12V_STBY_PVDDQ_GHJ")
		)
		(pad "2" smd rect
			(at 0 1.27508 270)
			(size 2.6924 1.3462)
			(layers "F.Cu" "F.Mask" "F.Paste")
			(net "GND")
		)
	)
	(footprint ""
		(layer "F.Cu")
		(at 483.38486 -28.14828 90)
		(property "Reference" "R8F25"
			(at 0 0 90)
			(layer "F.SilkS")
			(hide yes)
			(effects
				(font
					(size 1.27 1.27)
				)
			)
		)
		(property "Value" ""
			(at 0 0 90)
			(layer "F.Fab")
			(effects
				(font
					(size 1.27 1.27)
				)
			)
		)
		(duplicate_pad_numbers_are_jumpers no)
		(fp_poly
			(pts
				(xy -0.2794 -0.1016) (xy 0.2794 -0.1016) (xy 0.2794 0.9906) (xy -0.2794 0.9906)
			)
			(stroke
				(width 0)
				(type default)
			)
			(fill no)
			(layer "F.CrtYd")
		)
		(fp_line
			(start 0.2794 -0.1016)
			(end -0.2794 -0.1016)
			(stroke
				(width 0.1)
				(type default)
			)
			(layer "F.Fab")
		)
		(fp_line
			(start -0.2794 -0.1016)
			(end -0.2794 0.9906)
			(stroke
				(width 0.1)
				(type default)
			)
			(layer "F.Fab")
		)
		(fp_line
			(start 0.2794 0.9906)
			(end 0.2794 -0.1016)
			(stroke
				(width 0.1)
				(type default)
			)
			(layer "F.Fab")
		)
		(fp_line
			(start -0.2794 0.9906)
			(end 0.2794 0.9906)
			(stroke
				(width 0.1)
				(type default)
			)
			(layer "F.Fab")
		)
		(pad "1" smd rect
			(at 0 0 90)
			(size 0.508 0.508)
			(layers "F.Cu" "F.Mask" "F.Paste")
			(net "A_COMP_CKMNG")
		)
		(pad "2" smd rect
			(at 0 0.889 90)
			(size 0.508 0.508)
			(layers "F.Cu" "F.Mask" "F.Paste")
			(net "GND")
		)
		(zone
			(layer "F.Cu")
			(hatch none 0.5)
			(connect_pads
				(clearance 0)
			)
			(min_thickness 0.25)
			(keepout
				(tracks allowed)
				(vias not_allowed)
				(pads allowed)
				(copperpour not_allowed)
				(footprints allowed)
			)
			(placement
				(enabled no)
				(sheetname "")
			)
			(fill
				(thermal_gap 0.5)
				(thermal_bridge_width 0.5)
				(island_removal_mode 0)
			)
			(polygon
				(pts
					(xy 483.63886 -27.89428) (xy 483.63886 -28.40228) (xy 484.01986 -28.40228) (xy 484.01986 -27.89428)
				)
			)
		)
		(zone
			(layer "F.Cu")
			(hatch none 0.5)
			(connect_pads
				(clearance 0)
			)
			(min_thickness 0.25)
			(keepout
				(tracks not_allowed)
				(vias allowed)
				(pads allowed)
				(copperpour not_allowed)
				(footprints allowed)
			)
			(placement
				(enabled no)
				(sheetname "")
			)
			(fill
				(thermal_gap 0.5)
				(thermal_bridge_width 0.5)
				(island_removal_mode 0)
			)
			(polygon
				(pts
					(xy 484.01986 -27.89428) (xy 484.01986 -28.40228) (xy 483.63886 -28.40228) (xy 483.63886 -27.89428)
				)
			)
		)
	)
)
